FILE_TYPE = CONNECTIVITY;
{Allegro Design Entry HDL 17.2-2016 S081 (4005846) 1/11/2022}
"PAGE_NUMBER" = 63;
0"NC";
1"UPI_CPU1_CPU0_P0P1_DP<23:0>";
2"UPI_CPU1_CPU0_P0P1_DN<23:0>";
3"UPI_CPU0_CPU1_P1P0_DP<23:0>";
4"UPI_CPU0_CPU1_P1P0_DN<23:0>";
5"UPI_CPU0_CPU1_P1P0_DN<23>";
6"UPI_CPU0_CPU1_P1P0_DN<22>";
7"UPI_CPU0_CPU1_P1P0_DN<21>";
8"UPI_CPU0_CPU1_P1P0_DN<20>";
9"UPI_CPU0_CPU1_P1P0_DN<19>";
10"UPI_CPU0_CPU1_P1P0_DN<18>";
11"UPI_CPU0_CPU1_P1P0_DN<17>";
12"UPI_CPU0_CPU1_P1P0_DN<16>";
13"UPI_CPU0_CPU1_P1P0_DN<15>";
14"UPI_CPU0_CPU1_P1P0_DN<14>";
15"UPI_CPU0_CPU1_P1P0_DN<13>";
16"UPI_CPU0_CPU1_P1P0_DN<12>";
17"UPI_CPU0_CPU1_P1P0_DN<11>";
18"UPI_CPU0_CPU1_P1P0_DN<10>";
19"UPI_CPU0_CPU1_P1P0_DN<9>";
20"UPI_CPU0_CPU1_P1P0_DN<8>";
21"UPI_CPU0_CPU1_P1P0_DN<7>";
22"UPI_CPU0_CPU1_P1P0_DN<6>";
23"UPI_CPU0_CPU1_P1P0_DN<5>";
24"UPI_CPU0_CPU1_P1P0_DN<4>";
25"UPI_CPU0_CPU1_P1P0_DN<3>";
26"UPI_CPU0_CPU1_P1P0_DN<2>";
27"UPI_CPU0_CPU1_P1P0_DN<1>";
28"UPI_CPU0_CPU1_P1P0_DN<0>";
29"UPI_CPU0_CPU1_P1P0_DP<23>";
30"UPI_CPU0_CPU1_P1P0_DP<22>";
31"UPI_CPU0_CPU1_P1P0_DP<21>";
32"UPI_CPU0_CPU1_P1P0_DP<20>";
33"UPI_CPU0_CPU1_P1P0_DP<19>";
34"UPI_CPU0_CPU1_P1P0_DP<18>";
35"UPI_CPU0_CPU1_P1P0_DP<17>";
36"UPI_CPU0_CPU1_P1P0_DP<16>";
37"UPI_CPU0_CPU1_P1P0_DP<15>";
38"UPI_CPU0_CPU1_P1P0_DP<14>";
39"UPI_CPU0_CPU1_P1P0_DP<13>";
40"UPI_CPU0_CPU1_P1P0_DP<12>";
41"UPI_CPU0_CPU1_P1P0_DP<11>";
42"UPI_CPU0_CPU1_P1P0_DP<10>";
43"UPI_CPU0_CPU1_P1P0_DP<9>";
44"UPI_CPU0_CPU1_P1P0_DP<8>";
45"UPI_CPU0_CPU1_P1P0_DP<7>";
46"UPI_CPU0_CPU1_P1P0_DP<6>";
47"UPI_CPU0_CPU1_P1P0_DP<5>";
48"UPI_CPU0_CPU1_P1P0_DP<4>";
49"UPI_CPU0_CPU1_P1P0_DP<3>";
50"UPI_CPU0_CPU1_P1P0_DP<2>";
51"UPI_CPU0_CPU1_P1P0_DP<1>";
52"UPI_CPU0_CPU1_P1P0_DP<0>";
53"UPI_CPU1_CPU0_P0P1_DN<23>";
54"UPI_CPU1_CPU0_P0P1_DN<22>";
55"UPI_CPU1_CPU0_P0P1_DN<21>";
56"UPI_CPU1_CPU0_P0P1_DN<20>";
57"UPI_CPU1_CPU0_P0P1_DN<19>";
58"UPI_CPU1_CPU0_P0P1_DN<18>";
59"UPI_CPU1_CPU0_P0P1_DN<17>";
60"UPI_CPU1_CPU0_P0P1_DN<16>";
61"UPI_CPU1_CPU0_P0P1_DN<15>";
62"UPI_CPU1_CPU0_P0P1_DN<14>";
63"UPI_CPU1_CPU0_P0P1_DN<13>";
64"UPI_CPU1_CPU0_P0P1_DN<12>";
65"UPI_CPU1_CPU0_P0P1_DN<11>";
66"UPI_CPU1_CPU0_P0P1_DN<10>";
67"UPI_CPU1_CPU0_P0P1_DN<9>";
68"UPI_CPU1_CPU0_P0P1_DN<8>";
69"UPI_CPU1_CPU0_P0P1_DN<7>";
70"UPI_CPU1_CPU0_P0P1_DN<6>";
71"UPI_CPU1_CPU0_P0P1_DN<5>";
72"UPI_CPU1_CPU0_P0P1_DN<4>";
73"UPI_CPU1_CPU0_P0P1_DN<3>";
74"UPI_CPU1_CPU0_P0P1_DN<2>";
75"UPI_CPU1_CPU0_P0P1_DN<1>";
76"UPI_CPU1_CPU0_P0P1_DN<0>";
77"UPI_CPU1_CPU0_P0P1_DP<23>";
78"UPI_CPU1_CPU0_P0P1_DP<22>";
79"UPI_CPU1_CPU0_P0P1_DP<21>";
80"UPI_CPU1_CPU0_P0P1_DP<20>";
81"UPI_CPU1_CPU0_P0P1_DP<19>";
82"UPI_CPU1_CPU0_P0P1_DP<18>";
83"UPI_CPU1_CPU0_P0P1_DP<17>";
84"UPI_CPU1_CPU0_P0P1_DP<16>";
85"UPI_CPU1_CPU0_P0P1_DP<15>";
86"UPI_CPU1_CPU0_P0P1_DP<14>";
87"UPI_CPU1_CPU0_P0P1_DP<13>";
88"UPI_CPU1_CPU0_P0P1_DP<12>";
89"UPI_CPU1_CPU0_P0P1_DP<11>";
90"UPI_CPU1_CPU0_P0P1_DP<10>";
91"UPI_CPU1_CPU0_P0P1_DP<9>";
92"UPI_CPU1_CPU0_P0P1_DP<8>";
93"UPI_CPU1_CPU0_P0P1_DP<7>";
94"UPI_CPU1_CPU0_P0P1_DP<6>";
95"UPI_CPU1_CPU0_P0P1_DP<5>";
96"UPI_CPU1_CPU0_P0P1_DP<4>";
97"UPI_CPU1_CPU0_P0P1_DP<3>";
98"UPI_CPU1_CPU0_P0P1_DP<2>";
99"UPI_CPU1_CPU0_P0P1_DP<1>";
100"UPI_CPU1_CPU0_P0P1_DP<0>";
%"TAP"
"1","(-600,1725)","2","standard","I1";
;
CDS_LIB"standard"
BODY_TYPE"PLUMBING"
HDL_TAP"TRUE";
"B \NAC \NWC"4;
"S \NAC"
BN"0"28;
%"TAP"
"1","(-600,2175)","2","standard","I10";
;
CDS_LIB"standard"
BODY_TYPE"PLUMBING"
HDL_TAP"TRUE";
"B \NAC \NWC"4;
"S \NAC"
BN"9"19;
%"TAP"
"1","(-600,2225)","2","standard","I11";
;
CDS_LIB"standard"
BODY_TYPE"PLUMBING"
HDL_TAP"TRUE";
"B \NAC \NWC"4;
"S \NAC"
BN"10"18;
%"TAP"
"1","(-600,2325)","2","standard","I12";
;
CDS_LIB"standard"
BODY_TYPE"PLUMBING"
HDL_TAP"TRUE";
"B \NAC \NWC"4;
"S \NAC"
BN"12"16;
%"TAP"
"1","(-600,2275)","2","standard","I13";
;
CDS_LIB"standard"
BODY_TYPE"PLUMBING"
HDL_TAP"TRUE";
"B \NAC \NWC"4;
"S \NAC"
BN"11"17;
%"TAP"
"1","(-600,2425)","2","standard","I14";
;
CDS_LIB"standard"
BODY_TYPE"PLUMBING"
HDL_TAP"TRUE";
"B \NAC \NWC"4;
"S \NAC"
BN"14"14;
%"TAP"
"1","(-600,2375)","2","standard","I15";
;
CDS_LIB"standard"
BODY_TYPE"PLUMBING"
HDL_TAP"TRUE";
"B \NAC \NWC"4;
"S \NAC"
BN"13"15;
%"TAP"
"1","(-600,2475)","2","standard","I16";
;
CDS_LIB"standard"
BODY_TYPE"PLUMBING"
HDL_TAP"TRUE";
"B \NAC \NWC"4;
"S \NAC"
BN"15"13;
%"TAP"
"1","(-600,2525)","2","standard","I19";
;
CDS_LIB"standard"
BODY_TYPE"PLUMBING"
HDL_TAP"TRUE";
"B \NAC \NWC"4;
"S \NAC"
BN"16"12;
%"TAP"
"1","(-600,1775)","2","standard","I2";
;
CDS_LIB"standard"
BODY_TYPE"PLUMBING"
HDL_TAP"TRUE";
"B \NAC \NWC"4;
"S \NAC"
BN"1"27;
%"TAP"
"1","(-600,2575)","2","standard","I20";
;
CDS_LIB"standard"
BODY_TYPE"PLUMBING"
HDL_TAP"TRUE";
"B \NAC \NWC"4;
"S \NAC"
BN"17"11;
%"TAP"
"1","(-600,2625)","2","standard","I21";
;
CDS_LIB"standard"
BODY_TYPE"PLUMBING"
HDL_TAP"TRUE";
"B \NAC \NWC"4;
"S \NAC"
BN"18"10;
%"TAP"
"1","(-600,2725)","2","standard","I22";
;
CDS_LIB"standard"
BODY_TYPE"PLUMBING"
HDL_TAP"TRUE";
"B \NAC \NWC"4;
"S \NAC"
BN"20"8;
%"TAP"
"1","(-600,2675)","2","standard","I23";
;
CDS_LIB"standard"
BODY_TYPE"PLUMBING"
HDL_TAP"TRUE";
"B \NAC \NWC"4;
"S \NAC"
BN"19"9;
%"TAP"
"1","(-600,2775)","2","standard","I24";
;
CDS_LIB"standard"
BODY_TYPE"PLUMBING"
HDL_TAP"TRUE";
"B \NAC \NWC"4;
"S \NAC"
BN"21"7;
%"TAP"
"1","(-600,2825)","2","standard","I25";
;
CDS_LIB"standard"
BODY_TYPE"PLUMBING"
HDL_TAP"TRUE";
"B \NAC \NWC"4;
"S \NAC"
BN"22"6;
%"TAP"
"1","(-600,2875)","2","standard","I26";
;
CDS_LIB"standard"
BODY_TYPE"PLUMBING"
HDL_TAP"TRUE";
"B \NAC \NWC"4;
"S \NAC"
BN"23"5;
%"TAP"
"1","(-600,2975)","2","standard","I27";
;
CDS_LIB"standard"
BODY_TYPE"PLUMBING"
HDL_TAP"TRUE";
"B \NAC \NWC"3;
"S \NAC"
BN"0"52;
%"TAP"
"1","(-600,3075)","2","standard","I28";
;
CDS_LIB"standard"
BODY_TYPE"PLUMBING"
HDL_TAP"TRUE";
"B \NAC \NWC"3;
"S \NAC"
BN"2"50;
%"TAP"
"1","(-600,3025)","2","standard","I29";
;
CDS_LIB"standard"
BODY_TYPE"PLUMBING"
HDL_TAP"TRUE";
"B \NAC \NWC"3;
"S \NAC"
BN"1"51;
%"TAP"
"1","(-600,1825)","2","standard","I3";
;
CDS_LIB"standard"
BODY_TYPE"PLUMBING"
HDL_TAP"TRUE";
"B \NAC \NWC"4;
"S \NAC"
BN"2"26;
%"TAP"
"1","(-600,3125)","2","standard","I30";
;
CDS_LIB"standard"
BODY_TYPE"PLUMBING"
HDL_TAP"TRUE";
"B \NAC \NWC"3;
"S \NAC"
BN"3"49;
%"TAP"
"1","(-600,3225)","2","standard","I31";
;
CDS_LIB"standard"
BODY_TYPE"PLUMBING"
HDL_TAP"TRUE";
"B \NAC \NWC"3;
"S \NAC"
BN"5"47;
%"TAP"
"1","(-600,3175)","2","standard","I32";
;
CDS_LIB"standard"
BODY_TYPE"PLUMBING"
HDL_TAP"TRUE";
"B \NAC \NWC"3;
"S \NAC"
BN"4"48;
%"TAP"
"1","(-600,3275)","2","standard","I33";
;
CDS_LIB"standard"
BODY_TYPE"PLUMBING"
HDL_TAP"TRUE";
"B \NAC \NWC"3;
"S \NAC"
BN"6"46;
%"TAP"
"1","(-600,3325)","2","standard","I34";
;
CDS_LIB"standard"
BODY_TYPE"PLUMBING"
HDL_TAP"TRUE";
"B \NAC \NWC"3;
"S \NAC"
BN"7"45;
%"TAP"
"1","(-600,3375)","2","standard","I35";
;
CDS_LIB"standard"
BODY_TYPE"PLUMBING"
HDL_TAP"TRUE";
"B \NAC \NWC"3;
"S \NAC"
BN"8"44;
%"TAP"
"1","(-600,3475)","2","standard","I36";
;
CDS_LIB"standard"
BODY_TYPE"PLUMBING"
HDL_TAP"TRUE";
"B \NAC \NWC"3;
"S \NAC"
BN"10"42;
%"TAP"
"1","(-600,3425)","2","standard","I37";
;
CDS_LIB"standard"
BODY_TYPE"PLUMBING"
HDL_TAP"TRUE";
"B \NAC \NWC"3;
"S \NAC"
BN"9"43;
%"TAP"
"1","(-600,3525)","2","standard","I38";
;
CDS_LIB"standard"
BODY_TYPE"PLUMBING"
HDL_TAP"TRUE";
"B \NAC \NWC"3;
"S \NAC"
BN"11"41;
%"TAP"
"1","(-600,3575)","2","standard","I39";
;
CDS_LIB"standard"
BODY_TYPE"PLUMBING"
HDL_TAP"TRUE";
"B \NAC \NWC"3;
"S \NAC"
BN"12"40;
%"TAP"
"1","(-600,1875)","2","standard","I4";
;
CDS_LIB"standard"
BODY_TYPE"PLUMBING"
HDL_TAP"TRUE";
"B \NAC \NWC"4;
"S \NAC"
BN"3"25;
%"TAP"
"1","(-600,3625)","2","standard","I40";
;
CDS_LIB"standard"
BODY_TYPE"PLUMBING"
HDL_TAP"TRUE";
"B \NAC \NWC"3;
"S \NAC"
BN"13"39;
%"TAP"
"1","(-600,3675)","2","standard","I41";
;
CDS_LIB"standard"
BODY_TYPE"PLUMBING"
HDL_TAP"TRUE";
"B \NAC \NWC"3;
"S \NAC"
BN"14"38;
%"TAP"
"1","(-600,3725)","2","standard","I42";
;
CDS_LIB"standard"
BODY_TYPE"PLUMBING"
HDL_TAP"TRUE";
"B \NAC \NWC"3;
"S \NAC"
BN"15"37;
%"TAP"
"1","(-600,3775)","2","standard","I43";
;
CDS_LIB"standard"
BODY_TYPE"PLUMBING"
HDL_TAP"TRUE";
"B \NAC \NWC"3;
"S \NAC"
BN"16"36;
%"TAP"
"1","(-600,3875)","2","standard","I44";
;
CDS_LIB"standard"
BODY_TYPE"PLUMBING"
HDL_TAP"TRUE";
"B \NAC \NWC"3;
"S \NAC"
BN"18"34;
%"TAP"
"1","(-600,3825)","2","standard","I45";
;
CDS_LIB"standard"
BODY_TYPE"PLUMBING"
HDL_TAP"TRUE";
"B \NAC \NWC"3;
"S \NAC"
BN"17"35;
%"TAP"
"1","(-600,3975)","2","standard","I46";
;
CDS_LIB"standard"
BODY_TYPE"PLUMBING"
HDL_TAP"TRUE";
"B \NAC \NWC"3;
"S \NAC"
BN"20"32;
%"TAP"
"1","(-600,3925)","2","standard","I47";
;
CDS_LIB"standard"
BODY_TYPE"PLUMBING"
HDL_TAP"TRUE";
"B \NAC \NWC"3;
"S \NAC"
BN"19"33;
%"TAP"
"1","(-600,4025)","2","standard","I48";
;
CDS_LIB"standard"
BODY_TYPE"PLUMBING"
HDL_TAP"TRUE";
"B \NAC \NWC"3;
"S \NAC"
BN"21"31;
%"TAP"
"1","(-600,4075)","2","standard","I49";
;
CDS_LIB"standard"
BODY_TYPE"PLUMBING"
HDL_TAP"TRUE";
"B \NAC \NWC"3;
"S \NAC"
BN"22"30;
%"TAP"
"1","(-600,1925)","2","standard","I5";
;
CDS_LIB"standard"
BODY_TYPE"PLUMBING"
HDL_TAP"TRUE";
"B \NAC \NWC"4;
"S \NAC"
BN"4"24;
%"TAP"
"1","(-600,4125)","2","standard","I50";
;
CDS_LIB"standard"
BODY_TYPE"PLUMBING"
HDL_TAP"TRUE";
"B \NAC \NWC"3;
"S \NAC"
BN"23"29;
%"SOCKET4677_AZIF0045P001C01CS"
"22","(1100,2925)","0","pure_quanta","I51";
;
PART_NUMBER"DGA^7000023"
VALUE"SOCKET4677_AZIF0045-P001C01CS"
MATERIAL"IO"
PART_TYPE"SMLF"
$LOCATION"U1"
CDS_LMAN_SYM_OUTLINE"-1050,1350,1050,-1350"
NEEDS_NO_SIZE"TRUE"
CDS_LIB"pure_quanta"
CDS_LOCATION"U1"
$SEC"22"
CDS_SEC"22";
"UPI0_TX_DP0"
$PN"J3"100;
"UPI0_TX_DP1"
$PN"L3"99;
"UPI0_TX_DP2"
$PN"P2"98;
"UPI0_TX_DP3"
$PN"R3"97;
"UPI0_TX_DP4"
$PN"V2"96;
"UPI0_TX_DP5"
$PN"W3"95;
"UPI0_TX_DP6"
$PN"AB2"94;
"UPI0_TX_DP7"
$PN"AC3"93;
"UPI0_TX_DP8"
$PN"AE1"92;
"UPI0_TX_DP9"
$PN"AG3"91;
"UPI0_TX_DP10"
$PN"AJ1"90;
"UPI0_TX_DP11"
$PN"AL3"89;
"UPI0_TX_DP12"
$PN"AN1"88;
"UPI0_TX_DP13"
$PN"AR3"87;
"UPI0_TX_DP14"
$PN"AV2"86;
"UPI0_TX_DP15"
$PN"AW3"85;
"UPI0_TX_DP16"
$PN"BA1"84;
"UPI0_TX_DP17"
$PN"BC3"83;
"UPI0_TX_DP18"
$PN"BE1"82;
"UPI0_TX_DP19"
$PN"BG3"81;
"UPI0_TX_DP20"
$PN"BJ1"80;
"UPI0_TX_DP21"
$PN"BL3"79;
"UPI0_TX_DP22"
$PN"BN3"78;
"UPI0_TX_DP23"
$PN"BU3"77;
"UPI0_TX_DN0"
$PN"K4"76;
"UPI0_TX_DN1"
$PN"M2"75;
"UPI0_TX_DN2"
$PN"N1"74;
"UPI0_TX_DN3"
$PN"T2"73;
"UPI0_TX_DN4"
$PN"U1"72;
"UPI0_TX_DN5"
$PN"Y2"71;
"UPI0_TX_DN6"
$PN"AA1"70;
"UPI0_TX_DN7"
$PN"AD2"69;
"UPI0_TX_DN8"
$PN"AF2"68;
"UPI0_TX_DN9"
$PN"AH2"67;
"UPI0_TX_DN10"
$PN"AK2"66;
"UPI0_TX_DN11"
$PN"AM2"65;
"UPI0_TX_DN12"
$PN"AP2"64;
"UPI0_TX_DN13"
$PN"AT2"63;
"UPI0_TX_DN14"
$PN"AU1"62;
"UPI0_TX_DN15"
$PN"AY2"61;
"UPI0_TX_DN16"
$PN"BB2"60;
"UPI0_TX_DN17"
$PN"BD2"59;
"UPI0_TX_DN18"
$PN"BF2"58;
"UPI0_TX_DN19"
$PN"BH2"57;
"UPI0_TX_DN20"
$PN"BK2"56;
"UPI0_TX_DN21"
$PN"BM2"55;
"UPI0_TX_DN22"
$PN"BR3"54;
"UPI0_TX_DN23"
$PN"BT2"53;
"UPI0_RX_DP0"
$PN"L7"52;
"UPI0_RX_DP1"
$PN"M6"51;
"UPI0_RX_DP2"
$PN"R7"50;
"UPI0_RX_DP3"
$PN"T6"49;
"UPI0_RX_DP4"
$PN"W7"48;
"UPI0_RX_DP5"
$PN"Y6"47;
"UPI0_RX_DP6"
$PN"AC7"46;
"UPI0_RX_DP7"
$PN"AD6"45;
"UPI0_RX_DP8"
$PN"AG7"44;
"UPI0_RX_DP9"
$PN"AJ5"43;
"UPI0_RX_DP10"
$PN"AL7"42;
"UPI0_RX_DP11"
$PN"AM6"41;
"UPI0_RX_DP12"
$PN"AR7"40;
"UPI0_RX_DP13"
$PN"AT6"39;
"UPI0_RX_DP14"
$PN"AW7"38;
"UPI0_RX_DP15"
$PN"AY6"37;
"UPI0_RX_DP16"
$PN"BC7"36;
"UPI0_RX_DP17"
$PN"BD6"35;
"UPI0_RX_DP18"
$PN"BG7"34;
"UPI0_RX_DP19"
$PN"BH6"33;
"UPI0_RX_DP20"
$PN"BL7"32;
"UPI0_RX_DP21"
$PN"BM6"31;
"UPI0_RX_DP22"
$PN"BP6"30;
"UPI0_RX_DP23"
$PN"BT6"29;
"UPI0_RX_DN0"
$PN"K6"28;
"UPI0_RX_DN1"
$PN"N5"27;
"UPI0_RX_DN2"
$PN"P6"26;
"UPI0_RX_DN3"
$PN"U5"25;
"UPI0_RX_DN4"
$PN"V6"24;
"UPI0_RX_DN5"
$PN"AA5"23;
"UPI0_RX_DN6"
$PN"AB6"22;
"UPI0_RX_DN7"
$PN"AE5"21;
"UPI0_RX_DN8"
$PN"AF6"20;
"UPI0_RX_DN9"
$PN"AH6"19;
"UPI0_RX_DN10"
$PN"AK6"18;
"UPI0_RX_DN11"
$PN"AN5"17;
"UPI0_RX_DN12"
$PN"AP6"16;
"UPI0_RX_DN13"
$PN"AU5"15;
"UPI0_RX_DN14"
$PN"AV6"14;
"UPI0_RX_DN15"
$PN"BA5"13;
"UPI0_RX_DN16"
$PN"BB6"12;
"UPI0_RX_DN17"
$PN"BE5"11;
"UPI0_RX_DN18"
$PN"BF6"10;
"UPI0_RX_DN19"
$PN"BJ5"9;
"UPI0_RX_DN20"
$PN"BK6"8;
"UPI0_RX_DN21"
$PN"BN5"7;
"UPI0_RX_DN22"
$PN"BR7"6;
"UPI0_RX_DN23"
$PN"BU5"5;
%"TAP"
"1","(2775,1725)","0","standard","I52";
;
CDS_LIB"standard"
BODY_TYPE"PLUMBING"
HDL_TAP"TRUE";
"B \NAC \NWC"2;
"S \NAC"
BN"0"76;
%"TAP"
"1","(2775,1775)","0","standard","I53";
;
CDS_LIB"standard"
BODY_TYPE"PLUMBING"
HDL_TAP"TRUE";
"B \NAC \NWC"2;
"S \NAC"
BN"1"75;
%"TAP"
"1","(2775,1825)","0","standard","I54";
;
CDS_LIB"standard"
BODY_TYPE"PLUMBING"
HDL_TAP"TRUE";
"B \NAC \NWC"2;
"S \NAC"
BN"2"74;
%"TAP"
"1","(2775,1975)","0","standard","I55";
;
CDS_LIB"standard"
BODY_TYPE"PLUMBING"
HDL_TAP"TRUE";
"B \NAC \NWC"2;
"S \NAC"
BN"5"71;
%"TAP"
"1","(2775,1925)","0","standard","I56";
;
CDS_LIB"standard"
BODY_TYPE"PLUMBING"
HDL_TAP"TRUE";
"B \NAC \NWC"2;
"S \NAC"
BN"4"72;
%"TAP"
"1","(2775,1875)","0","standard","I57";
;
CDS_LIB"standard"
BODY_TYPE"PLUMBING"
HDL_TAP"TRUE";
"B \NAC \NWC"2;
"S \NAC"
BN"3"73;
%"TAP"
"1","(2775,2025)","0","standard","I58";
;
CDS_LIB"standard"
BODY_TYPE"PLUMBING"
HDL_TAP"TRUE";
"B \NAC \NWC"2;
"S \NAC"
BN"6"70;
%"TAP"
"1","(2775,2075)","0","standard","I59";
;
CDS_LIB"standard"
BODY_TYPE"PLUMBING"
HDL_TAP"TRUE";
"B \NAC \NWC"2;
"S \NAC"
BN"7"69;
%"TAP"
"1","(-600,1975)","2","standard","I6";
;
CDS_LIB"standard"
BODY_TYPE"PLUMBING"
HDL_TAP"TRUE";
"B \NAC \NWC"4;
"S \NAC"
BN"5"23;
%"TAP"
"1","(2775,2225)","0","standard","I60";
;
CDS_LIB"standard"
BODY_TYPE"PLUMBING"
HDL_TAP"TRUE";
"B \NAC \NWC"2;
"S \NAC"
BN"10"66;
%"TAP"
"1","(2775,2125)","0","standard","I61";
;
CDS_LIB"standard"
BODY_TYPE"PLUMBING"
HDL_TAP"TRUE";
"B \NAC \NWC"2;
"S \NAC"
BN"8"68;
%"TAP"
"1","(2775,2175)","0","standard","I62";
;
CDS_LIB"standard"
BODY_TYPE"PLUMBING"
HDL_TAP"TRUE";
"B \NAC \NWC"2;
"S \NAC"
BN"9"67;
%"TAP"
"1","(2775,2325)","0","standard","I63";
;
CDS_LIB"standard"
BODY_TYPE"PLUMBING"
HDL_TAP"TRUE";
"B \NAC \NWC"2;
"S \NAC"
BN"12"64;
%"TAP"
"1","(2775,2275)","0","standard","I64";
;
CDS_LIB"standard"
BODY_TYPE"PLUMBING"
HDL_TAP"TRUE";
"B \NAC \NWC"2;
"S \NAC"
BN"11"65;
%"TAP"
"1","(2775,2475)","0","standard","I65";
;
CDS_LIB"standard"
BODY_TYPE"PLUMBING"
HDL_TAP"TRUE";
"B \NAC \NWC"2;
"S \NAC"
BN"15"61;
%"TAP"
"1","(2775,2375)","0","standard","I66";
;
CDS_LIB"standard"
BODY_TYPE"PLUMBING"
HDL_TAP"TRUE";
"B \NAC \NWC"2;
"S \NAC"
BN"13"63;
%"TAP"
"1","(2775,2425)","0","standard","I67";
;
CDS_LIB"standard"
BODY_TYPE"PLUMBING"
HDL_TAP"TRUE";
"B \NAC \NWC"2;
"S \NAC"
BN"14"62;
%"TAP"
"1","(2775,2575)","0","standard","I68";
;
CDS_LIB"standard"
BODY_TYPE"PLUMBING"
HDL_TAP"TRUE";
"B \NAC \NWC"2;
"S \NAC"
BN"17"59;
%"TAP"
"1","(2775,2525)","0","standard","I69";
;
CDS_LIB"standard"
BODY_TYPE"PLUMBING"
HDL_TAP"TRUE";
"B \NAC \NWC"2;
"S \NAC"
BN"16"60;
%"TAP"
"1","(-600,2075)","2","standard","I7";
;
CDS_LIB"standard"
BODY_TYPE"PLUMBING"
HDL_TAP"TRUE";
"B \NAC \NWC"4;
"S \NAC"
BN"7"21;
%"TAP"
"1","(2775,2625)","0","standard","I70";
;
CDS_LIB"standard"
BODY_TYPE"PLUMBING"
HDL_TAP"TRUE";
"B \NAC \NWC"2;
"S \NAC"
BN"18"58;
%"TAP"
"1","(2775,2675)","0","standard","I71";
;
CDS_LIB"standard"
BODY_TYPE"PLUMBING"
HDL_TAP"TRUE";
"B \NAC \NWC"2;
"S \NAC"
BN"19"57;
%"TAP"
"1","(2775,2725)","0","standard","I72";
;
CDS_LIB"standard"
BODY_TYPE"PLUMBING"
HDL_TAP"TRUE";
"B \NAC \NWC"2;
"S \NAC"
BN"20"56;
%"TAP"
"1","(2775,2875)","0","standard","I73";
;
CDS_LIB"standard"
BODY_TYPE"PLUMBING"
HDL_TAP"TRUE";
"B \NAC \NWC"2;
"S \NAC"
BN"23"53;
%"TAP"
"1","(2775,2775)","0","standard","I74";
;
CDS_LIB"standard"
BODY_TYPE"PLUMBING"
HDL_TAP"TRUE";
"B \NAC \NWC"2;
"S \NAC"
BN"21"55;
%"TAP"
"1","(2775,2975)","0","standard","I75";
;
CDS_LIB"standard"
BODY_TYPE"PLUMBING"
HDL_TAP"TRUE";
"B \NAC \NWC"1;
"S \NAC"
BN"0"100;
%"TAP"
"1","(2775,2825)","0","standard","I76";
;
CDS_LIB"standard"
BODY_TYPE"PLUMBING"
HDL_TAP"TRUE";
"B \NAC \NWC"2;
"S \NAC"
BN"22"54;
%"TAP"
"1","(2775,3075)","0","standard","I77";
;
CDS_LIB"standard"
BODY_TYPE"PLUMBING"
HDL_TAP"TRUE";
"B \NAC \NWC"1;
"S \NAC"
BN"2"98;
%"TAP"
"1","(2775,3025)","0","standard","I78";
;
CDS_LIB"standard"
BODY_TYPE"PLUMBING"
HDL_TAP"TRUE";
"B \NAC \NWC"1;
"S \NAC"
BN"1"99;
%"TAP"
"1","(2775,3225)","0","standard","I79";
;
CDS_LIB"standard"
BODY_TYPE"PLUMBING"
HDL_TAP"TRUE";
"B \NAC \NWC"1;
"S \NAC"
BN"5"95;
%"TAP"
"1","(-600,2025)","2","standard","I8";
;
CDS_LIB"standard"
BODY_TYPE"PLUMBING"
HDL_TAP"TRUE";
"B \NAC \NWC"4;
"S \NAC"
BN"6"22;
%"TAP"
"1","(2775,3125)","0","standard","I80";
;
CDS_LIB"standard"
BODY_TYPE"PLUMBING"
HDL_TAP"TRUE";
"B \NAC \NWC"1;
"S \NAC"
BN"3"97;
%"TAP"
"1","(2775,3175)","0","standard","I81";
;
CDS_LIB"standard"
BODY_TYPE"PLUMBING"
HDL_TAP"TRUE";
"B \NAC \NWC"1;
"S \NAC"
BN"4"96;
%"TAP"
"1","(2775,3425)","0","standard","I82";
;
CDS_LIB"standard"
BODY_TYPE"PLUMBING"
HDL_TAP"TRUE";
"B \NAC \NWC"1;
"S \NAC"
BN"9"91;
%"TAP"
"1","(2775,3475)","0","standard","I83";
;
CDS_LIB"standard"
BODY_TYPE"PLUMBING"
HDL_TAP"TRUE";
"B \NAC \NWC"1;
"S \NAC"
BN"10"90;
%"TAP"
"1","(2775,3375)","0","standard","I84";
;
CDS_LIB"standard"
BODY_TYPE"PLUMBING"
HDL_TAP"TRUE";
"B \NAC \NWC"1;
"S \NAC"
BN"8"92;
%"TAP"
"1","(2775,3325)","0","standard","I85";
;
CDS_LIB"standard"
BODY_TYPE"PLUMBING"
HDL_TAP"TRUE";
"B \NAC \NWC"1;
"S \NAC"
BN"7"93;
%"TAP"
"1","(2775,3275)","0","standard","I86";
;
CDS_LIB"standard"
BODY_TYPE"PLUMBING"
HDL_TAP"TRUE";
"B \NAC \NWC"1;
"S \NAC"
BN"6"94;
%"TAP"
"1","(2775,3525)","0","standard","I87";
;
CDS_LIB"standard"
BODY_TYPE"PLUMBING"
HDL_TAP"TRUE";
"B \NAC \NWC"1;
"S \NAC"
BN"11"89;
%"TAP"
"1","(2775,3575)","0","standard","I88";
;
CDS_LIB"standard"
BODY_TYPE"PLUMBING"
HDL_TAP"TRUE";
"B \NAC \NWC"1;
"S \NAC"
BN"12"88;
%"TAP"
"1","(2775,3625)","0","standard","I89";
;
CDS_LIB"standard"
BODY_TYPE"PLUMBING"
HDL_TAP"TRUE";
"B \NAC \NWC"1;
"S \NAC"
BN"13"87;
%"TAP"
"1","(-600,2125)","2","standard","I9";
;
CDS_LIB"standard"
BODY_TYPE"PLUMBING"
HDL_TAP"TRUE";
"B \NAC \NWC"4;
"S \NAC"
BN"8"20;
%"TAP"
"1","(2775,3725)","0","standard","I90";
;
CDS_LIB"standard"
BODY_TYPE"PLUMBING"
HDL_TAP"TRUE";
"B \NAC \NWC"1;
"S \NAC"
BN"15"85;
%"TAP"
"1","(2775,3775)","0","standard","I91";
;
CDS_LIB"standard"
BODY_TYPE"PLUMBING"
HDL_TAP"TRUE";
"B \NAC \NWC"1;
"S \NAC"
BN"16"84;
%"TAP"
"1","(2775,3675)","0","standard","I92";
;
CDS_LIB"standard"
BODY_TYPE"PLUMBING"
HDL_TAP"TRUE";
"B \NAC \NWC"1;
"S \NAC"
BN"14"86;
%"TAP"
"1","(2775,3975)","0","standard","I93";
;
CDS_LIB"standard"
BODY_TYPE"PLUMBING"
HDL_TAP"TRUE";
"B \NAC \NWC"1;
"S \NAC"
BN"20"80;
%"TAP"
"1","(2775,3925)","0","standard","I94";
;
CDS_LIB"standard"
BODY_TYPE"PLUMBING"
HDL_TAP"TRUE";
"B \NAC \NWC"1;
"S \NAC"
BN"19"81;
%"TAP"
"1","(2775,4025)","0","standard","I95";
;
CDS_LIB"standard"
BODY_TYPE"PLUMBING"
HDL_TAP"TRUE";
"B \NAC \NWC"1;
"S \NAC"
BN"21"79;
%"TAP"
"1","(2775,3875)","0","standard","I96";
;
CDS_LIB"standard"
BODY_TYPE"PLUMBING"
HDL_TAP"TRUE";
"B \NAC \NWC"1;
"S \NAC"
BN"18"82;
%"TAP"
"1","(2775,3825)","0","standard","I97";
;
CDS_LIB"standard"
BODY_TYPE"PLUMBING"
HDL_TAP"TRUE";
"B \NAC \NWC"1;
"S \NAC"
BN"17"83;
%"TAP"
"1","(2775,4125)","0","standard","I98";
;
CDS_LIB"standard"
BODY_TYPE"PLUMBING"
HDL_TAP"TRUE";
"B \NAC \NWC"1;
"S \NAC"
BN"23"77;
%"TAP"
"1","(2775,4075)","0","standard","I99";
;
CDS_LIB"standard"
BODY_TYPE"PLUMBING"
HDL_TAP"TRUE";
"B \NAC \NWC"1;
"S \NAC"
BN"22"78;
END.
